(kicad_pcb
	(version 20260206)
	(generator "pcbnew")
	(generator_version "10.0")
	(general
		(thickness 1.6)
		(legacy_teardrops no)
	)
	(paper "A4")
	(title_block
		(title "Bryce Canyon_F.DPB_16315-1-OCP.brd")
		(comment 1 "Bryce Canyon / footprints 2164-2171 of 2223")
	)
	(layers
		(0 "F.Cu" signal "TOP")
		(4 "In1.Cu" signal "L2GND")
		(6 "In2.Cu" signal "L3")
		(8 "In3.Cu" signal "L4GND")
		(10 "In4.Cu" signal "L5")
		(12 "In5.Cu" signal "L6VCC")
		(14 "In6.Cu" signal "L7VCC")
		(16 "In7.Cu" signal "L8")
		(18 "In8.Cu" signal "L9GND")
		(20 "In9.Cu" signal "L10")
		(22 "In10.Cu" signal "L11GND")
		(2 "B.Cu" signal "BOTTOM")
		(9 "F.Adhes" user "F.Adhesive")
		(11 "B.Adhes" user "B.Adhesive")
		(13 "F.Paste" user "Package Geometry/Pastemask Top")
		(15 "B.Paste" user "Package Geometry/Pastemask Bottom")
		(5 "F.SilkS" user "Ref Des/Silkscreen Top")
		(7 "B.SilkS" user "Ref Des/Silkscreen Bottom")
		(1 "F.Mask" user "Board Geometry/Soldermask Top")
		(3 "B.Mask" user "Board Geometry/Soldermask Bottom")
		(17 "Dwgs.User" user "User.Drawings")
		(19 "Cmts.User" user "User.Comments")
		(21 "Eco1.User" user "User.Eco1")
		(23 "Eco2.User" user "User.Eco2")
		(25 "Edge.Cuts" user "Board Geometry/Outline")
		(27 "Margin" user)
		(31 "F.CrtYd" user "Package Geometry/Place Bound Top")
		(29 "B.CrtYd" user "Package Geometry/Place Bound Bottom")
		(35 "F.Fab" user "Ref Des/Assembly Top")
		(33 "B.Fab" user "Ref Des/Assembly Bottom")
	)
	(footprint ""
		(layer "B.Cu")
		(at 362.6358 -141.7574 90)
		(property "Reference" "R1087"
			(at 0 0 90)
			(layer "B.SilkS")
			(hide yes)
			(effects
				(font
					(size 1.27 1.27)
				)
				(justify mirror)
			)
		)
		(property "Value" "10R2F-L-GP"
			(at -0.064008 -3.993896 90)
			(unlocked yes)
			(layer "B.Fab")
			(hide yes)
			(effects
				(font
					(size 1.016 1.016)
					(thickness 0.1524)
				)
				(justify mirror)
			)
		)
		(property "Device Type" "R402H14"
			(at -0.064008 -5.517896 90)
			(unlocked yes)
			(layer "B.Fab")
			(hide yes)
			(effects
				(font
					(size 1.016 1.016)
					(thickness 0.1524)
				)
				(justify mirror)
			)
		)
		(duplicate_pad_numbers_are_jumpers no)
		(fp_line
			(start 0.508 -0.9398)
			(end 0.508 0.9398)
			(stroke
				(width 0.1524)
				(type default)
			)
			(layer "B.SilkS")
		)
		(fp_line
			(start -0.508 -0.9398)
			(end 0.508 -0.9398)
			(stroke
				(width 0.1524)
				(type default)
			)
			(layer "B.SilkS")
		)
		(fp_rect
			(start 0.508 0.9398)
			(end -0.508 -0.9398)
			(stroke
				(width 0)
				(type default)
			)
			(fill no)
			(layer "B.CrtYd")
		)
		(fp_rect
			(start 0.508 0.9398)
			(end -0.508 -0.9398)
			(stroke
				(width 0)
				(type default)
			)
			(fill no)
			(layer "B.Fab")
		)
		(pad "1" smd custom
			(at 0 -0.4445 270)
			(size 0.1397 0.1397)
			(layers "B.Cu" "B.Mask" "B.Paste")
			(net "MB1_CM_SENSE_R1_N")
			(options
				(clearance outline)
				(anchor circle)
			)
			(primitives
				(gr_poly
					(pts
						(arc
							(start -0.1778 0.2794)
							(mid -0.249642 0.249642)
							(end -0.2794 0.1778)
						)
						(arc
							(start -0.2794 -0.1778)
							(mid -0.249642 -0.249642)
							(end -0.1778 -0.2794)
						)
						(arc
							(start 0.1778 -0.2794)
							(mid 0.249642 -0.249642)
							(end 0.2794 -0.1778)
						)
						(arc
							(start 0.2794 0.1778)
							(mid 0.249642 0.249642)
							(end 0.1778 0.2794)
						)
					)
					(width 0)
					(fill yes)
				)
			)
		)
		(pad "2" smd custom
			(at 0 0.4445 270)
			(size 0.1397 0.1397)
			(layers "B.Cu" "B.Mask" "B.Paste")
			(net "MB1_CM_SENSE_N")
			(options
				(clearance outline)
				(anchor circle)
			)
			(primitives
				(gr_poly
					(pts
						(arc
							(start -0.1778 0.2794)
							(mid -0.249642 0.249642)
							(end -0.2794 0.1778)
						)
						(arc
							(start -0.2794 -0.1778)
							(mid -0.249642 -0.249642)
							(end -0.1778 -0.2794)
						)
						(arc
							(start 0.1778 -0.2794)
							(mid 0.249642 -0.249642)
							(end 0.2794 -0.1778)
						)
						(arc
							(start 0.2794 0.1778)
							(mid 0.249642 0.249642)
							(end 0.1778 0.2794)
						)
					)
					(width 0)
					(fill yes)
				)
			)
		)
	)
	(footprint ""
		(layer "B.Cu")
		(at 40.5892 -142.4432 180)
		(property "Reference" "C617"
			(at 0 0 0)
			(layer "B.SilkS")
			(hide yes)
			(effects
				(font
					(size 1.27 1.27)
				)
				(justify mirror)
			)
		)
		(property "Value" "SCD1U16V2KX-3GP"
			(at -1.1811 -2.7051 180)
			(unlocked yes)
			(layer "B.Fab")
			(hide yes)
			(effects
				(font
					(size 1.016 1.016)
					(thickness 0.1524)
				)
				(justify mirror)
			)
		)
		(property "Device Type" "C402H22"
			(at -1.1811 -4.2291 180)
			(unlocked yes)
			(layer "B.Fab")
			(hide yes)
			(effects
				(font
					(size 1.016 1.016)
					(thickness 0.1524)
				)
				(justify mirror)
			)
		)
		(duplicate_pad_numbers_are_jumpers no)
		(fp_rect
			(start 0.4318 0.9525)
			(end -0.4318 -0.9525)
			(stroke
				(width 0)
				(type default)
			)
			(fill no)
			(layer "B.CrtYd")
		)
		(fp_rect
			(start 0.4318 0.9525)
			(end -0.4318 -0.9525)
			(stroke
				(width 0)
				(type default)
			)
			(fill no)
			(layer "B.Fab")
		)
		(pad "1" smd custom
			(at 0 -0.4445)
			(size 0.1524 0.1524)
			(layers "B.Cu" "B.Mask" "B.Paste")
			(net "P12V_A_VIN_U21")
			(options
				(clearance outline)
				(anchor circle)
			)
			(primitives
				(gr_poly
					(pts
						(arc
							(start 0.3048 0.2032)
							(mid 0.275042 0.275042)
							(end 0.2032 0.3048)
						)
						(arc
							(start -0.2032 0.3048)
							(mid -0.275042 0.275042)
							(end -0.3048 0.2032)
						)
						(arc
							(start -0.3048 -0.2032)
							(mid -0.275042 -0.275042)
							(end -0.2032 -0.3048)
						)
						(arc
							(start 0.2032 -0.3048)
							(mid 0.275042 -0.275042)
							(end 0.3048 -0.2032)
						)
					)
					(width 0)
					(fill yes)
				)
			)
		)
		(pad "2" smd custom
			(at 0 0.4445)
			(size 0.1524 0.1524)
			(layers "B.Cu" "B.Mask" "B.Paste")
			(net "GND")
			(options
				(clearance outline)
				(anchor circle)
			)
			(primitives
				(gr_poly
					(pts
						(arc
							(start 0.3048 0.2032)
							(mid 0.275042 0.275042)
							(end 0.2032 0.3048)
						)
						(arc
							(start -0.2032 0.3048)
							(mid -0.275042 0.275042)
							(end -0.3048 0.2032)
						)
						(arc
							(start -0.3048 -0.2032)
							(mid -0.275042 -0.275042)
							(end -0.2032 -0.3048)
						)
						(arc
							(start 0.2032 -0.3048)
							(mid 0.275042 -0.275042)
							(end 0.3048 -0.2032)
						)
					)
					(width 0)
					(fill yes)
				)
			)
		)
	)
	(footprint ""
		(layer "B.Cu")
		(at 40.198802 -146.23415 -90)
		(property "Reference" "C621"
			(at 0 0 90)
			(layer "B.SilkS")
			(hide yes)
			(effects
				(font
					(size 1.27 1.27)
				)
				(justify mirror)
			)
		)
		(property "Value" "SC4D7U25V5KX-GP"
			(at 0.0762 -6.1214 270)
			(unlocked yes)
			(layer "B.Fab")
			(hide yes)
			(effects
				(font
					(size 1.016 1.016)
					(thickness 0.1524)
				)
				(justify mirror)
			)
		)
		(property "Device Type" "C805H54"
			(at 0.0762 -8.1534 270)
			(unlocked yes)
			(layer "B.Fab")
			(hide yes)
			(effects
				(font
					(size 1.016 1.016)
					(thickness 0.1524)
				)
				(justify mirror)
			)
		)
		(duplicate_pad_numbers_are_jumpers no)
		(fp_line
			(start -0.635 0)
			(end 0.635 0)
			(stroke
				(width 0.508)
				(type default)
			)
			(layer "B.SilkS")
		)
		(fp_rect
			(start 0.9652 1.778)
			(end -0.9652 -1.778)
			(stroke
				(width 0)
				(type default)
			)
			(fill no)
			(layer "B.CrtYd")
		)
		(fp_poly
			(pts
				(xy 0.9652 -1.778) (xy -0.9652 -1.778) (xy -0.9652 1.778) (xy 0.9652 1.778)
			)
			(stroke
				(width 0)
				(type default)
			)
			(fill no)
			(layer "B.Fab")
		)
		(pad "1" smd rect
			(at 0 -0.9652 90)
			(size 1.397 1.143)
			(layers "B.Cu" "B.Mask" "B.Paste")
			(net "P12V_A_VDD_U21")
		)
		(pad "2" smd rect
			(at 0 0.9652 90)
			(size 1.397 1.143)
			(layers "B.Cu" "B.Mask" "B.Paste")
			(net "GND")
		)
	)
	(footprint ""
		(layer "B.Cu")
		(at 167.699944 -164.200078 180)
		(property "Reference" "NUT4"
			(at 0 0 0)
			(layer "B.SilkS")
			(hide yes)
			(effects
				(font
					(size 1.27 1.27)
				)
				(justify mirror)
			)
		)
		(property "Value" "STF256R168H278-GP"
			(at 4.826 0.0508 180)
			(unlocked yes)
			(layer "B.Fab")
			(hide yes)
			(effects
				(font
					(size 1.016 1.016)
					(thickness 0.1524)
				)
				(justify mirror)
			)
		)
		(property "Device Type" "STF256R168H278"
			(at 4.826 -1.4732 180)
			(unlocked yes)
			(layer "B.Fab")
			(hide yes)
			(effects
				(font
					(size 1.016 1.016)
					(thickness 0.1524)
				)
				(justify mirror)
			)
		)
		(duplicate_pad_numbers_are_jumpers no)
		(fp_circle
			(center 0 0)
			(end -3.6068 0)
			(stroke
				(width 0.3048)
				(type default)
			)
			(fill no)
			(layer "B.SilkS")
		)
		(fp_poly
			(pts
				(arc
					(start -2.5019 0)
					(mid 2.5019 0)
					(end -2.5019 0)
				)
			)
			(stroke
				(width 0)
				(type default)
			)
			(fill no)
			(layer "B.CrtYd")
		)
		(fp_poly
			(pts
				(arc
					(start -3.7592 0.00635)
					(mid 3.759205 0)
					(end -3.7592 -0.00635)
				)
				(arc
					(start -2.5019 -0.00635)
					(mid 2.501908 0)
					(end -2.5019 0.00635)
				)
			)
			(stroke
				(width 0)
				(type default)
			)
			(fill no)
			(layer "B.CrtYd")
		)
		(fp_poly
			(pts
				(arc
					(start -3.7592 0)
					(mid 3.7592 0)
					(end -3.7592 0)
				)
			)
			(stroke
				(width 0)
				(type default)
			)
			(fill no)
			(layer "F.CrtYd")
		)
		(fp_poly
			(pts
				(arc
					(start -3.7592 0)
					(mid 3.7592 0)
					(end -3.7592 0)
				)
			)
			(stroke
				(width 0)
				(type default)
			)
			(fill no)
			(layer "B.Fab")
		)
		(fp_poly
			(pts
				(arc
					(start -3.7592 0)
					(mid 3.7592 0)
					(end -3.7592 0)
				)
			)
			(stroke
				(width 0)
				(type default)
			)
			(fill no)
			(layer "F.Fab")
		)
		(pad "1" thru_hole circle
			(at 0 0)
			(size 6.5024 6.5024)
			(drill 4.2672)
			(layers "*.Cu" "*.Mask")
			(remove_unused_layers no)
			(net "Net_12")
			(clearance -0.6096)
			(padstack
				(mode front_inner_back)
				(layer "Inner"
					(shape circle)
					(size 4.6736 4.6736)
					(clearance 0.3048)
				)
				(layer "B.Cu"
					(shape circle)
					(size 6.5024 6.5024)
					(thermal_gap 0.3048)
					(clearance -0.6096)
				)
			)
		)
	)
	(footprint ""
		(layer "B.Cu")
		(at 179.662328 -239.192308 180)
		(property "Reference" "C680"
			(at 0 0 0)
			(layer "B.SilkS")
			(hide yes)
			(effects
				(font
					(size 1.27 1.27)
				)
				(justify mirror)
			)
		)
		(property "Value" "SCD1U16V2KX-3GP"
			(at -1.1811 -2.7051 180)
			(unlocked yes)
			(layer "B.Fab")
			(hide yes)
			(effects
				(font
					(size 1.016 1.016)
					(thickness 0.1524)
				)
				(justify mirror)
			)
		)
		(property "Device Type" "C402H22"
			(at -1.1811 -4.2291 180)
			(unlocked yes)
			(layer "B.Fab")
			(hide yes)
			(effects
				(font
					(size 1.016 1.016)
					(thickness 0.1524)
				)
				(justify mirror)
			)
		)
		(duplicate_pad_numbers_are_jumpers no)
		(fp_rect
			(start 0.4318 0.9525)
			(end -0.4318 -0.9525)
			(stroke
				(width 0)
				(type default)
			)
			(fill no)
			(layer "B.CrtYd")
		)
		(fp_rect
			(start 0.4318 0.9525)
			(end -0.4318 -0.9525)
			(stroke
				(width 0)
				(type default)
			)
			(fill no)
			(layer "B.Fab")
		)
		(pad "1" smd custom
			(at 0 -0.4445)
			(size 0.1524 0.1524)
			(layers "B.Cu" "B.Mask" "B.Paste")
			(net "P3V3_STBY_A")
			(options
				(clearance outline)
				(anchor circle)
			)
			(primitives
				(gr_poly
					(pts
						(arc
							(start 0.3048 0.2032)
							(mid 0.275042 0.275042)
							(end 0.2032 0.3048)
						)
						(arc
							(start -0.2032 0.3048)
							(mid -0.275042 0.275042)
							(end -0.3048 0.2032)
						)
						(arc
							(start -0.3048 -0.2032)
							(mid -0.275042 -0.275042)
							(end -0.2032 -0.3048)
						)
						(arc
							(start 0.2032 -0.3048)
							(mid 0.275042 -0.275042)
							(end 0.3048 -0.2032)
						)
					)
					(width 0)
					(fill yes)
				)
			)
		)
		(pad "2" smd custom
			(at 0 0.4445)
			(size 0.1524 0.1524)
			(layers "B.Cu" "B.Mask" "B.Paste")
			(net "GND")
			(options
				(clearance outline)
				(anchor circle)
			)
			(primitives
				(gr_poly
					(pts
						(arc
							(start 0.3048 0.2032)
							(mid 0.275042 0.275042)
							(end 0.2032 0.3048)
						)
						(arc
							(start -0.2032 0.3048)
							(mid -0.275042 0.275042)
							(end -0.3048 0.2032)
						)
						(arc
							(start -0.3048 -0.2032)
							(mid -0.275042 -0.275042)
							(end -0.2032 -0.3048)
						)
						(arc
							(start 0.2032 -0.3048)
							(mid 0.275042 -0.275042)
							(end 0.3048 -0.2032)
						)
					)
					(width 0)
					(fill yes)
				)
			)
		)
	)
	(footprint ""
		(layer "B.Cu")
		(at 186.329828 -219.869004)
		(property "Reference" "C676"
			(at 0 0 0)
			(layer "B.SilkS")
			(hide yes)
			(effects
				(font
					(size 1.27 1.27)
				)
				(justify mirror)
			)
		)
		(property "Value" "SC1U16V3KX-5GP"
			(at 0 -2.8194 0)
			(unlocked yes)
			(layer "B.Fab")
			(hide yes)
			(effects
				(font
					(size 1.016 1.016)
					(thickness 0.1524)
				)
				(justify mirror)
			)
		)
		(property "Device Type" "C603H36"
			(at 0 -4.3434 0)
			(unlocked yes)
			(layer "B.Fab")
			(hide yes)
			(effects
				(font
					(size 1.016 1.016)
					(thickness 0.1524)
				)
				(justify mirror)
			)
		)
		(duplicate_pad_numbers_are_jumpers no)
		(fp_line
			(start -0.508 0)
			(end 0.508 0)
			(stroke
				(width 0.2032)
				(type default)
			)
			(layer "B.SilkS")
		)
		(fp_rect
			(start 0.5842 1.3335)
			(end -0.5842 -1.3335)
			(stroke
				(width 0)
				(type default)
			)
			(fill no)
			(layer "B.CrtYd")
		)
		(fp_rect
			(start 0.5842 1.3335)
			(end -0.5842 -1.3335)
			(stroke
				(width 0)
				(type default)
			)
			(fill no)
			(layer "B.Fab")
		)
		(pad "1" smd custom
			(at 0 -0.762 180)
			(size 0.2159 0.2159)
			(layers "B.Cu" "B.Mask" "B.Paste")
			(net "P3V3_STBY_VRG5")
			(options
				(clearance outline)
				(anchor circle)
			)
			(primitives
				(gr_poly
					(pts
						(arc
							(start -0.3302 0.4318)
							(mid -0.402042 0.402042)
							(end -0.4318 0.3302)
						)
						(arc
							(start -0.4318 -0.3302)
							(mid -0.402042 -0.402042)
							(end -0.3302 -0.4318)
						)
						(arc
							(start 0.3302 -0.4318)
							(mid 0.402042 -0.402042)
							(end 0.4318 -0.3302)
						)
						(arc
							(start 0.4318 0.3302)
							(mid 0.402042 0.402042)
							(end 0.3302 0.4318)
						)
					)
					(width 0)
					(fill yes)
				)
			)
		)
		(pad "2" smd custom
			(at 0 0.762 180)
			(size 0.2159 0.2159)
			(layers "B.Cu" "B.Mask" "B.Paste")
			(net "GND")
			(options
				(clearance outline)
				(anchor circle)
			)
			(primitives
				(gr_poly
					(pts
						(arc
							(start -0.3302 0.4318)
							(mid -0.402042 0.402042)
							(end -0.4318 0.3302)
						)
						(arc
							(start -0.4318 -0.3302)
							(mid -0.402042 -0.402042)
							(end -0.3302 -0.4318)
						)
						(arc
							(start 0.3302 -0.4318)
							(mid 0.402042 -0.402042)
							(end 0.4318 -0.3302)
						)
						(arc
							(start 0.4318 0.3302)
							(mid 0.402042 0.402042)
							(end 0.3302 0.4318)
						)
					)
					(width 0)
					(fill yes)
				)
			)
		)
	)
	(footprint ""
		(layer "B.Cu")
		(at 194.009772 -224.256092)
		(property "Reference" "R1282"
			(at 0 0 0)
			(layer "B.SilkS")
			(hide yes)
			(effects
				(font
					(size 1.27 1.27)
				)
				(justify mirror)
			)
		)
		(property "Value" "0R6J-3-GP"
			(at 0.0508 -4.8514 0)
			(unlocked yes)
			(layer "B.Fab")
			(hide yes)
			(effects
				(font
					(size 1.016 1.016)
					(thickness 0.1524)
				)
				(justify mirror)
			)
		)
		(property "Device Type" "R1206H28"
			(at 0 -6.3754 0)
			(unlocked yes)
			(layer "B.Fab")
			(hide yes)
			(effects
				(font
					(size 1.016 1.016)
					(thickness 0.1524)
				)
				(justify mirror)
			)
		)
		(duplicate_pad_numbers_are_jumpers no)
		(fp_line
			(start -1.016 -2.2352)
			(end -1.016 2.2352)
			(stroke
				(width 0.1524)
				(type default)
			)
			(layer "B.SilkS")
		)
		(fp_line
			(start -1.016 2.2352)
			(end 1.016 2.2352)
			(stroke
				(width 0.1524)
				(type default)
			)
			(layer "B.SilkS")
		)
		(fp_line
			(start 1.016 -2.2352)
			(end -1.016 -2.2352)
			(stroke
				(width 0.1524)
				(type default)
			)
			(layer "B.SilkS")
		)
		(fp_line
			(start 1.016 2.2352)
			(end 1.016 -2.2352)
			(stroke
				(width 0.1524)
				(type default)
			)
			(layer "B.SilkS")
		)
		(fp_rect
			(start 1.0922 2.3114)
			(end -1.0922 -2.3114)
			(stroke
				(width 0)
				(type default)
			)
			(fill no)
			(layer "B.CrtYd")
		)
		(fp_poly
			(pts
				(xy 1.0922 -2.3114) (xy -1.0922 -2.3114) (xy -1.0922 2.3114) (xy 1.0922 2.3114)
			)
			(stroke
				(width 0)
				(type default)
			)
			(fill no)
			(layer "B.Fab")
		)
		(pad "1" smd rect
			(at 0 -1.397 180)
			(size 1.651 1.27)
			(layers "B.Cu" "B.Mask" "B.Paste")
			(net "P3V3_STBY_VIN")
		)
		(pad "2" smd rect
			(at 0 1.397 180)
			(size 1.651 1.27)
			(layers "B.Cu" "B.Mask" "B.Paste")
			(net "P12V_A")
		)
	)
	(footprint ""
		(layer "B.Cu")
		(at 189.911482 -232.661206 90)
		(property "Reference" "R1289"
			(at 0 0 90)
			(layer "B.SilkS")
			(hide yes)
			(effects
				(font
					(size 1.27 1.27)
				)
				(justify mirror)
			)
		)
		(property "Value" "2KR2F-3-GP"
			(at -0.064008 -3.993896 90)
			(unlocked yes)
			(layer "B.Fab")
			(hide yes)
			(effects
				(font
					(size 1.016 1.016)
					(thickness 0.1524)
				)
				(justify mirror)
			)
		)
		(property "Device Type" "R402H16"
			(at -0.064008 -5.517896 90)
			(unlocked yes)
			(layer "B.Fab")
			(hide yes)
			(effects
				(font
					(size 1.016 1.016)
					(thickness 0.1524)
				)
				(justify mirror)
			)
		)
		(duplicate_pad_numbers_are_jumpers no)
		(fp_line
			(start 0.508 -0.9398)
			(end 0.508 0.9398)
			(stroke
				(width 0.1524)
				(type default)
			)
			(layer "B.SilkS")
		)
		(fp_line
			(start -0.508 -0.9398)
			(end 0.508 -0.9398)
			(stroke
				(width 0.1524)
				(type default)
			)
			(layer "B.SilkS")
		)
		(fp_rect
			(start 0.508 0.9398)
			(end -0.508 -0.9398)
			(stroke
				(width 0)
				(type default)
			)
			(fill no)
			(layer "B.CrtYd")
		)
		(fp_rect
			(start 0.508 0.9398)
			(end -0.508 -0.9398)
			(stroke
				(width 0)
				(type default)
			)
			(fill no)
			(layer "B.Fab")
		)
		(pad "1" smd custom
			(at 0 -0.4445 270)
			(size 0.1397 0.1397)
			(layers "B.Cu" "B.Mask" "B.Paste")
			(net "P3V3_STBY_SW")
			(options
				(clearance outline)
				(anchor circle)
			)
			(primitives
				(gr_poly
					(pts
						(arc
							(start -0.1778 0.2794)
							(mid -0.249642 0.249642)
							(end -0.2794 0.1778)
						)
						(arc
							(start -0.2794 -0.1778)
							(mid -0.249642 -0.249642)
							(end -0.1778 -0.2794)
						)
						(arc
							(start 0.1778 -0.2794)
							(mid 0.249642 -0.249642)
							(end 0.2794 -0.1778)
						)
						(arc
							(start 0.2794 0.1778)
							(mid 0.249642 0.249642)
							(end 0.1778 0.2794)
						)
					)
					(width 0)
					(fill yes)
				)
			)
		)
		(pad "2" smd custom
			(at 0 0.4445 270)
			(size 0.1397 0.1397)
			(layers "B.Cu" "B.Mask" "B.Paste")
			(net "P3V3_STBY_VFB_R")
			(options
				(clearance outline)
				(anchor circle)
			)
			(primitives
				(gr_poly
					(pts
						(arc
							(start -0.1778 0.2794)
							(mid -0.249642 0.249642)
							(end -0.2794 0.1778)
						)
						(arc
							(start -0.2794 -0.1778)
							(mid -0.249642 -0.249642)
							(end -0.1778 -0.2794)
						)
						(arc
							(start 0.1778 -0.2794)
							(mid 0.249642 -0.249642)
							(end 0.2794 -0.1778)
						)
						(arc
							(start 0.2794 0.1778)
							(mid 0.249642 0.249642)
							(end 0.1778 0.2794)
						)
					)
					(width 0)
					(fill yes)
				)
			)
		)
	)
)
